# BASEBOARD_FAB2 (Tioga Pass) — schematic netlist excerpt (pin names and nets, part order shuffled) for the footprints in the layout excerpt that follows; sources: Cadence DE-HDL packaged netlist, KiCad conversion of Wiwynn_Tioga_Pass_MB.brd

C2N10  CAP_A  22.0UF 4V 20% X6S  pkg 0603V  page 131 : A = P1V05_PCH_STBY ; B = GND
R6N9  RES  10.0 1% CHIP  pkg 0402  page 163 : A = SMB_CPU1_PE_HP_GTL_SDA ; B = SMB_CPU1_PE_HP_GTL_R_SDA
R6P10  RES  0.0 5% CHIP  pkg 0402  page 203 : A = VR_PVCCIN_CPU0_PH4_VCIN ; B = P5V_STBY

(kicad_pcb
	(version 20260206)
	(generator "pcbnew")
	(generator_version "10.0")
	(general
		(thickness 1.6)
		(legacy_teardrops no)
	)
	(paper "A4")
	(title_block
		(title "Wiwynn_Tioga_Pass_MB.brd")
		(comment 1 "Tioga Pass / footprints 4742-4744 of 4770")
	)
	(layers
		(0 "F.Cu" signal "TOP")
		(4 "In1.Cu" signal "L2GND")
		(6 "In2.Cu" signal "L3")
		(8 "In3.Cu" signal "L4GND")
		(10 "In4.Cu" signal "L5")
		(12 "In5.Cu" signal "L6GND")
		(14 "In6.Cu" signal "L7VCC")
		(16 "In7.Cu" signal "L8VCC")
		(18 "In8.Cu" signal "L9GND")
		(20 "In9.Cu" signal "L10")
		(22 "In10.Cu" signal "L11GND")
		(24 "In11.Cu" signal "L12")
		(26 "In12.Cu" signal "L13GND")
		(2 "B.Cu" signal "BOTTOM")
		(9 "F.Adhes" user "F.Adhesive")
		(11 "B.Adhes" user "B.Adhesive")
		(13 "F.Paste" user "Package Geometry/Pastemask Top")
		(15 "B.Paste" user "Package Geometry/Pastemask Bottom")
		(5 "F.SilkS" user "Ref Des/Silkscreen Top")
		(7 "B.SilkS" user "Ref Des/Silkscreen Bottom")
		(1 "F.Mask" user "Board Geometry/Soldermask Top")
		(3 "B.Mask" user "Board Geometry/Soldermask Bottom")
		(17 "Dwgs.User" user "User.Drawings")
		(19 "Cmts.User" user "User.Comments")
		(21 "Eco1.User" user "User.Eco1")
		(23 "Eco2.User" user "User.Eco2")
		(25 "Edge.Cuts" user "Board Geometry/Outline")
		(27 "Margin" user)
		(31 "F.CrtYd" user "Package Geometry/Place Bound Top")
		(29 "B.CrtYd" user "Package Geometry/Place Bound Bottom")
		(35 "F.Fab" user "Ref Des/Assembly Top")
		(33 "B.Fab" user "Ref Des/Assembly Bottom")
	)
	(footprint ""
		(layer "B.Cu")
		(at 197.239128 -78.915006 90)
		(property "Reference" "R6P10"
			(at 0 0 90)
			(layer "B.SilkS")
			(hide yes)
			(effects
				(font
					(size 1.27 1.27)
				)
				(justify mirror)
			)
		)
		(property "Value" ""
			(at 0 0 90)
			(layer "B.Fab")
			(effects
				(font
					(size 1.27 1.27)
				)
				(justify mirror)
			)
		)
		(duplicate_pad_numbers_are_jumpers no)
		(fp_rect
			(start 0.2794 -0.1016)
			(end -0.2794 0.9906)
			(stroke
				(width 0)
				(type default)
			)
			(fill no)
			(layer "B.CrtYd")
		)
		(fp_line
			(start 0.2794 -0.1016)
			(end 0.2794 0.9906)
			(stroke
				(width 0.1)
				(type default)
			)
			(layer "B.Fab")
		)
		(fp_line
			(start -0.2794 -0.1016)
			(end 0.2794 -0.1016)
			(stroke
				(width 0.1)
				(type default)
			)
			(layer "B.Fab")
		)
		(fp_line
			(start 0.2794 0.9906)
			(end -0.2794 0.9906)
			(stroke
				(width 0.1)
				(type default)
			)
			(layer "B.Fab")
		)
		(fp_line
			(start -0.2794 0.9906)
			(end -0.2794 -0.1016)
			(stroke
				(width 0.1)
				(type default)
			)
			(layer "B.Fab")
		)
		(pad "1" smd rect
			(at 0 0 270)
			(size 0.508 0.508)
			(layers "B.Cu" "B.Mask" "B.Paste")
			(net "VR_PVCCIN_CPU0_PH4_VCIN")
		)
		(pad "2" smd rect
			(at 0 0.889 270)
			(size 0.508 0.508)
			(layers "B.Cu" "B.Mask" "B.Paste")
			(net "P5V_STBY")
		)
		(zone
			(layer "B.Cu")
			(hatch none 0.5)
			(connect_pads
				(clearance 0)
			)
			(min_thickness 0.25)
			(keepout
				(tracks allowed)
				(vias not_allowed)
				(pads allowed)
				(copperpour not_allowed)
				(footprints allowed)
			)
			(placement
				(enabled no)
				(sheetname "")
			)
			(fill
				(thermal_gap 0.5)
				(thermal_bridge_width 0.5)
				(island_removal_mode 0)
			)
			(polygon
				(pts
					(xy 197.493128 -79.169006) (xy 197.493128 -78.661006) (xy 197.874128 -78.661006) (xy 197.874128 -79.169006)
				)
			)
		)
		(zone
			(layer "B.Cu")
			(hatch none 0.5)
			(connect_pads
				(clearance 0)
			)
			(min_thickness 0.25)
			(keepout
				(tracks not_allowed)
				(vias allowed)
				(pads allowed)
				(copperpour not_allowed)
				(footprints allowed)
			)
			(placement
				(enabled no)
				(sheetname "")
			)
			(fill
				(thermal_gap 0.5)
				(thermal_bridge_width 0.5)
				(island_removal_mode 0)
			)
			(polygon
				(pts
					(xy 197.493128 -79.169006) (xy 197.493128 -78.661006) (xy 197.874128 -78.661006) (xy 197.874128 -79.169006)
				)
			)
		)
	)
	(footprint ""
		(layer "B.Cu")
		(at 176.022 -88.646 180)
		(property "Reference" "R6N9"
			(at 0 0 0)
			(layer "B.SilkS")
			(hide yes)
			(effects
				(font
					(size 1.27 1.27)
				)
				(justify mirror)
			)
		)
		(property "Value" ""
			(at 0 0 0)
			(layer "B.Fab")
			(effects
				(font
					(size 1.27 1.27)
				)
				(justify mirror)
			)
		)
		(duplicate_pad_numbers_are_jumpers no)
		(fp_poly
			(pts
				(xy 0.2794 -0.1016) (xy -0.2794 -0.1016) (xy -0.2794 0.9906) (xy 0.2794 0.9906)
			)
			(stroke
				(width 0)
				(type default)
			)
			(fill no)
			(layer "B.CrtYd")
		)
		(fp_line
			(start 0.2794 0.9906)
			(end -0.2794 0.9906)
			(stroke
				(width 0.1)
				(type default)
			)
			(layer "B.Fab")
		)
		(fp_line
			(start 0.2794 -0.1016)
			(end 0.2794 0.9906)
			(stroke
				(width 0.1)
				(type default)
			)
			(layer "B.Fab")
		)
		(fp_line
			(start -0.2794 0.9906)
			(end -0.2794 -0.1016)
			(stroke
				(width 0.1)
				(type default)
			)
			(layer "B.Fab")
		)
		(fp_line
			(start -0.2794 -0.1016)
			(end 0.2794 -0.1016)
			(stroke
				(width 0.1)
				(type default)
			)
			(layer "B.Fab")
		)
		(pad "1" smd rect
			(at 0 0)
			(size 0.508 0.508)
			(layers "B.Cu" "B.Mask" "B.Paste")
			(net "SMB_CPU1_PE_HP_GTL_SDA")
		)
		(pad "2" smd rect
			(at 0 0.889)
			(size 0.508 0.508)
			(layers "B.Cu" "B.Mask" "B.Paste")
			(net "SMB_CPU1_PE_HP_GTL_R_SDA")
		)
		(zone
			(layer "B.Cu")
			(hatch none 0.5)
			(connect_pads
				(clearance 0)
			)
			(min_thickness 0.25)
			(keepout
				(tracks not_allowed)
				(vias allowed)
				(pads allowed)
				(copperpour not_allowed)
				(footprints allowed)
			)
			(placement
				(enabled no)
				(sheetname "")
			)
			(fill
				(thermal_gap 0.5)
				(thermal_bridge_width 0.5)
				(island_removal_mode 0)
			)
			(polygon
				(pts
					(xy 175.768 -89.281) (xy 176.276 -89.281) (xy 176.276 -88.9) (xy 175.768 -88.9)
				)
			)
		)
		(zone
			(layer "B.Cu")
			(hatch none 0.5)
			(connect_pads
				(clearance 0)
			)
			(min_thickness 0.25)
			(keepout
				(tracks allowed)
				(vias not_allowed)
				(pads allowed)
				(copperpour not_allowed)
				(footprints allowed)
			)
			(placement
				(enabled no)
				(sheetname "")
			)
			(fill
				(thermal_gap 0.5)
				(thermal_bridge_width 0.5)
				(island_removal_mode 0)
			)
			(polygon
				(pts
					(xy 175.768 -88.9) (xy 176.276 -88.9) (xy 176.276 -89.281) (xy 175.768 -89.281)
				)
			)
		)
	)
	(footprint ""
		(layer "B.Cu")
		(at 400.177 -108.077 180)
		(property "Reference" "C2N10"
			(at 0 0 0)
			(layer "B.SilkS")
			(hide yes)
			(effects
				(font
					(size 1.27 1.27)
				)
				(justify mirror)
			)
		)
		(property "Value" ""
			(at 0 0 0)
			(layer "B.Fab")
			(effects
				(font
					(size 1.27 1.27)
				)
				(justify mirror)
			)
		)
		(duplicate_pad_numbers_are_jumpers no)
		(fp_poly
			(pts
				(xy 0.4953 -0.2032) (xy -0.4953 -0.2032) (xy -0.4953 1.6002) (xy 0.4953 1.6002)
			)
			(stroke
				(width 0)
				(type default)
			)
			(fill no)
			(layer "B.CrtYd")
		)
		(fp_line
			(start 0.4953 1.6002)
			(end 0.4953 -0.2032)
			(stroke
				(width 0.1)
				(type default)
			)
			(layer "B.Fab")
		)
		(fp_line
			(start 0.4953 -0.2032)
			(end -0.4953 -0.2032)
			(stroke
				(width 0.1)
				(type default)
			)
			(layer "B.Fab")
		)
		(fp_line
			(start -0.4953 1.6002)
			(end 0.4953 1.6002)
			(stroke
				(width 0.1)
				(type default)
			)
			(layer "B.Fab")
		)
		(fp_line
			(start -0.4953 -0.2032)
			(end -0.4953 1.6002)
			(stroke
				(width 0.1)
				(type default)
			)
			(layer "B.Fab")
		)
		(pad "1" smd rect
			(at 0 0)
			(size 0.762 0.889)
			(layers "B.Cu" "B.Mask" "B.Paste")
			(net "P1V05_PCH_STBY")
		)
		(pad "2" smd rect
			(at 0 1.397)
			(size 0.762 0.889)
			(layers "B.Cu" "B.Mask" "B.Paste")
			(net "GND")
		)
		(zone
			(layer "B.Cu")
			(hatch none 0.5)
			(connect_pads
				(clearance 0)
			)
			(min_thickness 0.25)
			(keepout
				(tracks not_allowed)
				(vias allowed)
				(pads allowed)
				(copperpour not_allowed)
				(footprints allowed)
			)
			(placement
				(enabled no)
				(sheetname "")
			)
			(fill
				(thermal_gap 0.5)
				(thermal_bridge_width 0.5)
				(island_removal_mode 0)
			)
			(polygon
				(pts
					(xy 399.796 -108.5215) (xy 400.558 -108.5215) (xy 400.558 -109.0295) (xy 399.796 -109.0295)
				)
			)
		)
	)
)
